# S9S_MB_2U (Grand Teton) — schematic netlist excerpt (pin names and nets, part order shuffled) for the footprints in the layout excerpt that follows; sources: Cadence DE-HDL packaged netlist, KiCad conversion of 03242023_DA0F0TMBIJ0_F0T_Motherboard_J_brd_V01_OCP.brd

R263  Q_RES  240 1% EMPTY  pkg 0402LF  page 119 : A = PVNN_TERM_CPU1 ; B = PU_CPU1_FRMAGENT
PR2525  Q_RES  10 1% EMPTY  pkg 0402LF  page 304 : A = P12V_HSC_SENSE2_N ; B = P12V_HSC_SENSE2_R2_N

(kicad_pcb
	(version 20260206)
	(generator "pcbnew")
	(generator_version "10.0")
	(general
		(thickness 1.6)
		(legacy_teardrops no)
	)
	(paper "A4")
	(title_block
		(title "03242023_DA0F0TMBIJ0_F0T_Motherboard_J_brd_V01_OCP.brd")
		(comment 1 "Grand Teton / footprints 4733-4734 of 6105")
	)
	(layers
		(0 "F.Cu" signal "TOP")
		(4 "In1.Cu" signal "GND")
		(6 "In2.Cu" signal "IN1")
		(8 "In3.Cu" signal "GND1")
		(10 "In4.Cu" signal "IN2")
		(12 "In5.Cu" signal "GND2")
		(14 "In6.Cu" signal "IN3")
		(16 "In7.Cu" signal "GND3")
		(18 "In8.Cu" signal "VCC")
		(20 "In9.Cu" signal "VCC1")
		(22 "In10.Cu" signal "GND4")
		(24 "In11.Cu" signal "IN4")
		(26 "In12.Cu" signal "GND5")
		(28 "In13.Cu" signal "IN5")
		(30 "In14.Cu" signal "GND6")
		(32 "In15.Cu" signal "IN6")
		(34 "In16.Cu" signal "GND7")
		(2 "B.Cu" signal "BOTTOM")
		(9 "F.Adhes" user "F.Adhesive")
		(11 "B.Adhes" user "B.Adhesive")
		(13 "F.Paste" user "Package Geometry/Pastemask Top")
		(15 "B.Paste" user "Package Geometry/Pastemask Bottom")
		(5 "F.SilkS" user "Ref Des/Silkscreen Top")
		(7 "B.SilkS" user "Ref Des/Silkscreen Bottom")
		(1 "F.Mask" user "Board Geometry/Soldermask Top")
		(3 "B.Mask" user "Board Geometry/Soldermask Bottom")
		(17 "Dwgs.User" user "User.Drawings")
		(19 "Cmts.User" user "User.Comments")
		(21 "Eco1.User" user "User.Eco1")
		(23 "Eco2.User" user "User.Eco2")
		(25 "Edge.Cuts" user "Board Geometry/Outline")
		(27 "Margin" user)
		(31 "F.CrtYd" user "Package Geometry/Place Bound Top")
		(29 "B.CrtYd" user "Package Geometry/Place Bound Bottom")
		(35 "F.Fab" user "Ref Des/Assembly Top")
		(33 "B.Fab" user "Ref Des/Assembly Bottom")
	)
	(footprint ""
		(layer "B.Cu")
		(at 83.082384 -188.035692 -90)
		(property "Reference" "R263"
			(at 0 0 90)
			(layer "B.SilkS")
			(hide yes)
			(effects
				(font
					(size 1.27 1.27)
				)
				(justify mirror)
			)
		)
		(property "Value" ""
			(at 0 0 90)
			(layer "B.Fab")
			(effects
				(font
					(size 1.27 1.27)
				)
				(justify mirror)
			)
		)
		(duplicate_pad_numbers_are_jumpers no)
		(fp_line
			(start -0.7874 0.4064)
			(end 0.7874 0.4064)
			(stroke
				(width 0.1524)
				(type default)
			)
			(layer "B.SilkS")
		)
		(fp_line
			(start 0.7874 0.4064)
			(end 0.7874 -0.4064)
			(stroke
				(width 0.1524)
				(type default)
			)
			(layer "B.SilkS")
		)
		(fp_line
			(start -0.7874 -0.4064)
			(end -0.7874 0.4064)
			(stroke
				(width 0.1524)
				(type default)
			)
			(layer "B.SilkS")
		)
		(fp_line
			(start 0.7874 -0.4064)
			(end -0.7874 -0.4064)
			(stroke
				(width 0.1524)
				(type default)
			)
			(layer "B.SilkS")
		)
		(fp_line
			(start -0.67945 0.3048)
			(end -0.120396 0.3048)
			(stroke
				(width 0.1)
				(type default)
			)
			(layer "B.Fab")
		)
		(fp_line
			(start -0.120396 0.3048)
			(end -0.120396 0.2794)
			(stroke
				(width 0.1)
				(type default)
			)
			(layer "B.Fab")
		)
		(fp_line
			(start 0.12065 0.3048)
			(end 0.67945 0.3048)
			(stroke
				(width 0.1)
				(type default)
			)
			(layer "B.Fab")
		)
		(fp_line
			(start 0.67945 0.3048)
			(end 0.67945 -0.305054)
			(stroke
				(width 0.1)
				(type default)
			)
			(layer "B.Fab")
		)
		(fp_line
			(start -0.120396 0.2794)
			(end 0.12065 0.2794)
			(stroke
				(width 0.1)
				(type default)
			)
			(layer "B.Fab")
		)
		(fp_line
			(start 0.12065 0.2794)
			(end 0.12065 0.3048)
			(stroke
				(width 0.1)
				(type default)
			)
			(layer "B.Fab")
		)
		(fp_line
			(start -0.12065 -0.2794)
			(end -0.12065 -0.3048)
			(stroke
				(width 0.1)
				(type default)
			)
			(layer "B.Fab")
		)
		(fp_line
			(start 0.12065 -0.2794)
			(end -0.12065 -0.2794)
			(stroke
				(width 0.1)
				(type default)
			)
			(layer "B.Fab")
		)
		(fp_line
			(start -0.67945 -0.3048)
			(end -0.67945 0.3048)
			(stroke
				(width 0.1)
				(type default)
			)
			(layer "B.Fab")
		)
		(fp_line
			(start -0.12065 -0.3048)
			(end -0.67945 -0.3048)
			(stroke
				(width 0.1)
				(type default)
			)
			(layer "B.Fab")
		)
		(fp_line
			(start 0.12065 -0.305054)
			(end 0.12065 -0.2794)
			(stroke
				(width 0.1)
				(type default)
			)
			(layer "B.Fab")
		)
		(fp_line
			(start 0.67945 -0.305054)
			(end 0.12065 -0.305054)
			(stroke
				(width 0.1)
				(type default)
			)
			(layer "B.Fab")
		)
		(pad "1" smd circle
			(at 0.40005 0 90)
			(size 0 0)
			(layers "B.Cu" "B.Mask" "B.Paste")
			(net "PVNN_TERM_CPU1")
		)
		(pad "2" smd circle
			(at -0.40005 0 90)
			(size 0 0)
			(layers "B.Cu" "B.Mask" "B.Paste")
			(net "PU_CPU1_FRMAGENT")
		)
	)
	(footprint ""
		(layer "B.Cu")
		(at 289.988498 -400.999452 -90)
		(property "Reference" "PR2525"
			(at 0 0 90)
			(layer "B.SilkS")
			(hide yes)
			(effects
				(font
					(size 1.27 1.27)
				)
				(justify mirror)
			)
		)
		(property "Value" ""
			(at 0 0 90)
			(layer "B.Fab")
			(effects
				(font
					(size 1.27 1.27)
				)
				(justify mirror)
			)
		)
		(duplicate_pad_numbers_are_jumpers no)
		(fp_line
			(start -0.7874 0.4064)
			(end 0.7874 0.4064)
			(stroke
				(width 0.1524)
				(type default)
			)
			(layer "B.SilkS")
		)
		(fp_line
			(start 0.7874 0.4064)
			(end 0.7874 -0.4064)
			(stroke
				(width 0.1524)
				(type default)
			)
			(layer "B.SilkS")
		)
		(fp_line
			(start -0.7874 -0.4064)
			(end -0.7874 0.4064)
			(stroke
				(width 0.1524)
				(type default)
			)
			(layer "B.SilkS")
		)
		(fp_line
			(start 0.7874 -0.4064)
			(end -0.7874 -0.4064)
			(stroke
				(width 0.1524)
				(type default)
			)
			(layer "B.SilkS")
		)
		(fp_line
			(start -0.67945 0.3048)
			(end -0.120396 0.3048)
			(stroke
				(width 0.1)
				(type default)
			)
			(layer "B.Fab")
		)
		(fp_line
			(start -0.120396 0.3048)
			(end -0.120396 0.2794)
			(stroke
				(width 0.1)
				(type default)
			)
			(layer "B.Fab")
		)
		(fp_line
			(start 0.12065 0.3048)
			(end 0.67945 0.3048)
			(stroke
				(width 0.1)
				(type default)
			)
			(layer "B.Fab")
		)
		(fp_line
			(start 0.67945 0.3048)
			(end 0.67945 -0.305054)
			(stroke
				(width 0.1)
				(type default)
			)
			(layer "B.Fab")
		)
		(fp_line
			(start -0.120396 0.2794)
			(end 0.12065 0.2794)
			(stroke
				(width 0.1)
				(type default)
			)
			(layer "B.Fab")
		)
		(fp_line
			(start 0.12065 0.2794)
			(end 0.12065 0.3048)
			(stroke
				(width 0.1)
				(type default)
			)
			(layer "B.Fab")
		)
		(fp_line
			(start -0.12065 -0.2794)
			(end -0.12065 -0.3048)
			(stroke
				(width 0.1)
				(type default)
			)
			(layer "B.Fab")
		)
		(fp_line
			(start 0.12065 -0.2794)
			(end -0.12065 -0.2794)
			(stroke
				(width 0.1)
				(type default)
			)
			(layer "B.Fab")
		)
		(fp_line
			(start -0.67945 -0.3048)
			(end -0.67945 0.3048)
			(stroke
				(width 0.1)
				(type default)
			)
			(layer "B.Fab")
		)
		(fp_line
			(start -0.12065 -0.3048)
			(end -0.67945 -0.3048)
			(stroke
				(width 0.1)
				(type default)
			)
			(layer "B.Fab")
		)
		(fp_line
			(start 0.12065 -0.305054)
			(end 0.12065 -0.2794)
			(stroke
				(width 0.1)
				(type default)
			)
			(layer "B.Fab")
		)
		(fp_line
			(start 0.67945 -0.305054)
			(end 0.12065 -0.305054)
			(stroke
				(width 0.1)
				(type default)
			)
			(layer "B.Fab")
		)
		(pad "1" smd circle
			(at 0.40005 0 90)
			(size 0 0)
			(layers "B.Cu" "B.Mask" "B.Paste")
			(net "P12V_HSC_SENSE2_N")
		)
		(pad "2" smd circle
			(at -0.40005 0 90)
			(size 0 0)
			(layers "B.Cu" "B.Mask" "B.Paste")
			(net "P12V_HSC_SENSE2_R2_N")
		)
	)
)
